(kicad_pcb
	(version 20260206)
	(generator "pcbnew")
	(generator_version "10.0")
	(general
		(thickness 1.6)
		(legacy_teardrops no)
	)
	(paper "A4")
	(title_block
		(title "04192023_DAF0TMB3IC0_F0TG_MB_C_brd_V02_OCP.brd")
		(comment 1 "Grand Teton / footprints 6596-6602 of 8354")
	)
	(layers
		(0 "F.Cu" signal "TOP")
		(4 "In1.Cu" signal "GND")
		(6 "In2.Cu" signal "IN1")
		(8 "In3.Cu" signal "GND1")
		(10 "In4.Cu" signal "IN2")
		(12 "In5.Cu" signal "GND2")
		(14 "In6.Cu" signal "IN3")
		(16 "In7.Cu" signal "GND3")
		(18 "In8.Cu" signal "VCC")
		(20 "In9.Cu" signal "VCC1")
		(22 "In10.Cu" signal "GND4")
		(24 "In11.Cu" signal "IN4")
		(26 "In12.Cu" signal "GND5")
		(28 "In13.Cu" signal "IN5")
		(30 "In14.Cu" signal "GND6")
		(32 "In15.Cu" signal "IN6")
		(34 "In16.Cu" signal "GND7")
		(2 "B.Cu" signal "BOTTOM")
		(9 "F.Adhes" user "F.Adhesive")
		(11 "B.Adhes" user "B.Adhesive")
		(13 "F.Paste" user "Package Geometry/Pastemask Top")
		(15 "B.Paste" user "Package Geometry/Pastemask Bottom")
		(5 "F.SilkS" user "Ref Des/Silkscreen Top")
		(7 "B.SilkS" user "Ref Des/Silkscreen Bottom")
		(1 "F.Mask" user "Board Geometry/Soldermask Top")
		(3 "B.Mask" user "Board Geometry/Soldermask Bottom")
		(17 "Dwgs.User" user "User.Drawings")
		(19 "Cmts.User" user "User.Comments")
		(21 "Eco1.User" user "User.Eco1")
		(23 "Eco2.User" user "User.Eco2")
		(25 "Edge.Cuts" user "Board Geometry/Outline")
		(27 "Margin" user)
		(31 "F.CrtYd" user "Package Geometry/Place Bound Top")
		(29 "B.CrtYd" user "Package Geometry/Place Bound Bottom")
		(35 "F.Fab" user "Ref Des/Assembly Top")
		(33 "B.Fab" user "Ref Des/Assembly Bottom")
	)
	(footprint ""
		(layer "B.Cu")
		(at 179.705 -100.294948 -90)
		(property "Reference" "R137"
			(at 0 0 90)
			(layer "B.SilkS")
			(hide yes)
			(effects
				(font
					(size 1.27 1.27)
				)
				(justify mirror)
			)
		)
		(property "Value" ""
			(at 0 0 90)
			(layer "B.Fab")
			(effects
				(font
					(size 1.27 1.27)
				)
				(justify mirror)
			)
		)
		(duplicate_pad_numbers_are_jumpers no)
		(fp_line
			(start -0.7874 0.4064)
			(end 0.7874 0.4064)
			(stroke
				(width 0.1524)
				(type default)
			)
			(layer "B.SilkS")
		)
		(fp_line
			(start 0.7874 0.4064)
			(end 0.7874 -0.4064)
			(stroke
				(width 0.1524)
				(type default)
			)
			(layer "B.SilkS")
		)
		(fp_line
			(start -0.7874 -0.4064)
			(end -0.7874 0.4064)
			(stroke
				(width 0.1524)
				(type default)
			)
			(layer "B.SilkS")
		)
		(fp_line
			(start 0.7874 -0.4064)
			(end -0.7874 -0.4064)
			(stroke
				(width 0.1524)
				(type default)
			)
			(layer "B.SilkS")
		)
		(fp_line
			(start -0.67945 0.3048)
			(end -0.120396 0.3048)
			(stroke
				(width 0.1)
				(type default)
			)
			(layer "B.Fab")
		)
		(fp_line
			(start -0.120396 0.3048)
			(end -0.120396 0.2794)
			(stroke
				(width 0.1)
				(type default)
			)
			(layer "B.Fab")
		)
		(fp_line
			(start 0.12065 0.3048)
			(end 0.67945 0.3048)
			(stroke
				(width 0.1)
				(type default)
			)
			(layer "B.Fab")
		)
		(fp_line
			(start 0.67945 0.3048)
			(end 0.67945 -0.305054)
			(stroke
				(width 0.1)
				(type default)
			)
			(layer "B.Fab")
		)
		(fp_line
			(start -0.120396 0.2794)
			(end 0.12065 0.2794)
			(stroke
				(width 0.1)
				(type default)
			)
			(layer "B.Fab")
		)
		(fp_line
			(start 0.12065 0.2794)
			(end 0.12065 0.3048)
			(stroke
				(width 0.1)
				(type default)
			)
			(layer "B.Fab")
		)
		(fp_line
			(start -0.12065 -0.2794)
			(end -0.12065 -0.3048)
			(stroke
				(width 0.1)
				(type default)
			)
			(layer "B.Fab")
		)
		(fp_line
			(start 0.12065 -0.2794)
			(end -0.12065 -0.2794)
			(stroke
				(width 0.1)
				(type default)
			)
			(layer "B.Fab")
		)
		(fp_line
			(start -0.67945 -0.3048)
			(end -0.67945 0.3048)
			(stroke
				(width 0.1)
				(type default)
			)
			(layer "B.Fab")
		)
		(fp_line
			(start -0.12065 -0.3048)
			(end -0.67945 -0.3048)
			(stroke
				(width 0.1)
				(type default)
			)
			(layer "B.Fab")
		)
		(fp_line
			(start 0.12065 -0.305054)
			(end 0.12065 -0.2794)
			(stroke
				(width 0.1)
				(type default)
			)
			(layer "B.Fab")
		)
		(fp_line
			(start 0.67945 -0.305054)
			(end 0.12065 -0.305054)
			(stroke
				(width 0.1)
				(type default)
			)
			(layer "B.Fab")
		)
		(pad "1" smd circle
			(at 0.40005 0 90)
			(size 0 0)
			(layers "B.Cu" "B.Mask" "B.Paste")
			(net "PVDDCR_CPU1_P0_OCP_N")
		)
		(pad "2" smd circle
			(at -0.40005 0 90)
			(size 0 0)
			(layers "B.Cu" "B.Mask" "B.Paste")
			(net "FM_PVDDCR_CPU1_P0_OCP_N")
		)
	)
	(footprint ""
		(layer "B.Cu")
		(at 192.913 -100.294948 90)
		(property "Reference" "R220"
			(at 0 0 90)
			(layer "B.SilkS")
			(hide yes)
			(effects
				(font
					(size 1.27 1.27)
				)
				(justify mirror)
			)
		)
		(property "Value" ""
			(at 0 0 90)
			(layer "B.Fab")
			(effects
				(font
					(size 1.27 1.27)
				)
				(justify mirror)
			)
		)
		(duplicate_pad_numbers_are_jumpers no)
		(fp_line
			(start 0.7874 -0.4064)
			(end -0.7874 -0.4064)
			(stroke
				(width 0.1524)
				(type default)
			)
			(layer "B.SilkS")
		)
		(fp_line
			(start -0.7874 -0.4064)
			(end -0.7874 0.4064)
			(stroke
				(width 0.1524)
				(type default)
			)
			(layer "B.SilkS")
		)
		(fp_line
			(start 0.7874 0.4064)
			(end 0.7874 -0.4064)
			(stroke
				(width 0.1524)
				(type default)
			)
			(layer "B.SilkS")
		)
		(fp_line
			(start -0.7874 0.4064)
			(end 0.7874 0.4064)
			(stroke
				(width 0.1524)
				(type default)
			)
			(layer "B.SilkS")
		)
		(fp_line
			(start 0.67945 -0.305054)
			(end 0.12065 -0.305054)
			(stroke
				(width 0.1)
				(type default)
			)
			(layer "B.Fab")
		)
		(fp_line
			(start 0.12065 -0.305054)
			(end 0.12065 -0.2794)
			(stroke
				(width 0.1)
				(type default)
			)
			(layer "B.Fab")
		)
		(fp_line
			(start -0.12065 -0.3048)
			(end -0.67945 -0.3048)
			(stroke
				(width 0.1)
				(type default)
			)
			(layer "B.Fab")
		)
		(fp_line
			(start -0.67945 -0.3048)
			(end -0.67945 0.3048)
			(stroke
				(width 0.1)
				(type default)
			)
			(layer "B.Fab")
		)
		(fp_line
			(start 0.12065 -0.2794)
			(end -0.12065 -0.2794)
			(stroke
				(width 0.1)
				(type default)
			)
			(layer "B.Fab")
		)
		(fp_line
			(start -0.12065 -0.2794)
			(end -0.12065 -0.3048)
			(stroke
				(width 0.1)
				(type default)
			)
			(layer "B.Fab")
		)
		(fp_line
			(start 0.12065 0.2794)
			(end 0.12065 0.3048)
			(stroke
				(width 0.1)
				(type default)
			)
			(layer "B.Fab")
		)
		(fp_line
			(start -0.120396 0.2794)
			(end 0.12065 0.2794)
			(stroke
				(width 0.1)
				(type default)
			)
			(layer "B.Fab")
		)
		(fp_line
			(start 0.67945 0.3048)
			(end 0.67945 -0.305054)
			(stroke
				(width 0.1)
				(type default)
			)
			(layer "B.Fab")
		)
		(fp_line
			(start 0.12065 0.3048)
			(end 0.67945 0.3048)
			(stroke
				(width 0.1)
				(type default)
			)
			(layer "B.Fab")
		)
		(fp_line
			(start -0.120396 0.3048)
			(end -0.120396 0.2794)
			(stroke
				(width 0.1)
				(type default)
			)
			(layer "B.Fab")
		)
		(fp_line
			(start -0.67945 0.3048)
			(end -0.120396 0.3048)
			(stroke
				(width 0.1)
				(type default)
			)
			(layer "B.Fab")
		)
		(pad "1" smd circle
			(at 0.40005 0 270)
			(size 0 0)
			(layers "B.Cu" "B.Mask" "B.Paste")
			(net "FM_CPU0_SA0")
		)
		(pad "2" smd circle
			(at -0.40005 0 270)
			(size 0 0)
			(layers "B.Cu" "B.Mask" "B.Paste")
			(net "CPU0_SA0")
		)
	)
	(footprint ""
		(layer "B.Cu")
		(at 358.089454 -266.00531)
		(property "Reference" "C3934"
			(at 0 0 0)
			(layer "B.SilkS")
			(hide yes)
			(effects
				(font
					(size 1.27 1.27)
				)
				(justify mirror)
			)
		)
		(property "Value" ""
			(at 0 0 0)
			(layer "B.Fab")
			(effects
				(font
					(size 1.27 1.27)
				)
				(justify mirror)
			)
		)
		(duplicate_pad_numbers_are_jumpers no)
		(fp_line
			(start -0.7874 -0.4064)
			(end -0.7874 0.4064)
			(stroke
				(width 0.1524)
				(type default)
			)
			(layer "B.SilkS")
		)
		(fp_line
			(start -0.7874 0.4064)
			(end 0.7874 0.4064)
			(stroke
				(width 0.1524)
				(type default)
			)
			(layer "B.SilkS")
		)
		(fp_line
			(start 0.7874 -0.4064)
			(end -0.7874 -0.4064)
			(stroke
				(width 0.1524)
				(type default)
			)
			(layer "B.SilkS")
		)
		(fp_line
			(start 0.7874 0.4064)
			(end 0.7874 -0.4064)
			(stroke
				(width 0.1524)
				(type default)
			)
			(layer "B.SilkS")
		)
		(fp_line
			(start -0.67945 -0.3048)
			(end -0.67945 0.3048)
			(stroke
				(width 0.1)
				(type default)
			)
			(layer "B.Fab")
		)
		(fp_line
			(start -0.67945 0.3048)
			(end -0.120396 0.3048)
			(stroke
				(width 0.1)
				(type default)
			)
			(layer "B.Fab")
		)
		(fp_line
			(start -0.12065 -0.3048)
			(end -0.67945 -0.3048)
			(stroke
				(width 0.1)
				(type default)
			)
			(layer "B.Fab")
		)
		(fp_line
			(start -0.12065 -0.2794)
			(end -0.12065 -0.3048)
			(stroke
				(width 0.1)
				(type default)
			)
			(layer "B.Fab")
		)
		(fp_line
			(start -0.120396 0.2794)
			(end 0.12065 0.2794)
			(stroke
				(width 0.1)
				(type default)
			)
			(layer "B.Fab")
		)
		(fp_line
			(start -0.120396 0.3048)
			(end -0.120396 0.2794)
			(stroke
				(width 0.1)
				(type default)
			)
			(layer "B.Fab")
		)
		(fp_line
			(start 0.12065 -0.305054)
			(end 0.12065 -0.2794)
			(stroke
				(width 0.1)
				(type default)
			)
			(layer "B.Fab")
		)
		(fp_line
			(start 0.12065 -0.2794)
			(end -0.12065 -0.2794)
			(stroke
				(width 0.1)
				(type default)
			)
			(layer "B.Fab")
		)
		(fp_line
			(start 0.12065 0.2794)
			(end 0.12065 0.3048)
			(stroke
				(width 0.1)
				(type default)
			)
			(layer "B.Fab")
		)
		(fp_line
			(start 0.12065 0.3048)
			(end 0.67945 0.3048)
			(stroke
				(width 0.1)
				(type default)
			)
			(layer "B.Fab")
		)
		(fp_line
			(start 0.67945 -0.305054)
			(end 0.12065 -0.305054)
			(stroke
				(width 0.1)
				(type default)
			)
			(layer "B.Fab")
		)
		(fp_line
			(start 0.67945 0.3048)
			(end 0.67945 -0.305054)
			(stroke
				(width 0.1)
				(type default)
			)
			(layer "B.Fab")
		)
		(pad "1" smd circle
			(at 0.40005 0 180)
			(size 0 0)
			(layers "B.Cu" "B.Mask" "B.Paste")
			(net "PVDD11_S3_P0")
		)
		(pad "2" smd circle
			(at -0.40005 0 180)
			(size 0 0)
			(layers "B.Cu" "B.Mask" "B.Paste")
			(net "GND")
		)
	)
	(footprint ""
		(layer "B.Cu")
		(at 136.868154 -165.145212 90)
		(property "Reference" "PC354_3"
			(at 0 0 90)
			(layer "B.SilkS")
			(hide yes)
			(effects
				(font
					(size 1.27 1.27)
				)
				(justify mirror)
			)
		)
		(property "Value" ""
			(at 0 0 90)
			(layer "B.Fab")
			(effects
				(font
					(size 1.27 1.27)
				)
				(justify mirror)
			)
		)
		(duplicate_pad_numbers_are_jumpers no)
		(fp_line
			(start 1.524 -0.762)
			(end -1.524 -0.762)
			(stroke
				(width 0.1524)
				(type default)
			)
			(layer "B.SilkS")
		)
		(fp_line
			(start -1.524 -0.762)
			(end -1.524 0.762)
			(stroke
				(width 0.1524)
				(type default)
			)
			(layer "B.SilkS")
		)
		(fp_line
			(start 1.524 0.762)
			(end 1.524 -0.762)
			(stroke
				(width 0.1524)
				(type default)
			)
			(layer "B.SilkS")
		)
		(fp_line
			(start -1.524 0.762)
			(end 1.524 0.762)
			(stroke
				(width 0.1524)
				(type default)
			)
			(layer "B.SilkS")
		)
		(fp_line
			(start 1.1049 -0.724916)
			(end 1.1049 0.724916)
			(stroke
				(width 0.1)
				(type default)
			)
			(layer "B.Fab")
		)
		(fp_line
			(start -1.1049 -0.724916)
			(end 1.1049 -0.724916)
			(stroke
				(width 0.1)
				(type default)
			)
			(layer "B.Fab")
		)
		(fp_line
			(start 1.1049 0.724916)
			(end -1.1049 0.724916)
			(stroke
				(width 0.1)
				(type default)
			)
			(layer "B.Fab")
		)
		(fp_line
			(start -1.1049 0.724916)
			(end -1.1049 -0.724916)
			(stroke
				(width 0.1)
				(type default)
			)
			(layer "B.Fab")
		)
		(pad "1" smd rect
			(at 0.889 0 90)
			(size 1.016 1.27)
			(layers "B.Cu" "B.Mask" "B.Paste")
			(net "PVDDCR_SOC_P1")
		)
		(pad "2" smd rect
			(at -0.889 0 90)
			(size 1.016 1.27)
			(layers "B.Cu" "B.Mask" "B.Paste")
			(net "GND")
		)
	)
	(footprint ""
		(layer "B.Cu")
		(at 35.306 -361.95)
		(property "Reference" "PR230"
			(at 0 0 0)
			(layer "B.SilkS")
			(hide yes)
			(effects
				(font
					(size 1.27 1.27)
				)
				(justify mirror)
			)
		)
		(property "Value" ""
			(at 0 0 0)
			(layer "B.Fab")
			(effects
				(font
					(size 1.27 1.27)
				)
				(justify mirror)
			)
		)
		(duplicate_pad_numbers_are_jumpers no)
		(fp_line
			(start -0.7874 -0.4064)
			(end -0.7874 0.4064)
			(stroke
				(width 0.1524)
				(type default)
			)
			(layer "B.SilkS")
		)
		(fp_line
			(start -0.7874 0.4064)
			(end 0.7874 0.4064)
			(stroke
				(width 0.1524)
				(type default)
			)
			(layer "B.SilkS")
		)
		(fp_line
			(start 0.7874 -0.4064)
			(end -0.7874 -0.4064)
			(stroke
				(width 0.1524)
				(type default)
			)
			(layer "B.SilkS")
		)
		(fp_line
			(start 0.7874 0.4064)
			(end 0.7874 -0.4064)
			(stroke
				(width 0.1524)
				(type default)
			)
			(layer "B.SilkS")
		)
		(fp_line
			(start -0.67945 -0.3048)
			(end -0.67945 0.3048)
			(stroke
				(width 0.1)
				(type default)
			)
			(layer "B.Fab")
		)
		(fp_line
			(start -0.67945 0.3048)
			(end -0.120396 0.3048)
			(stroke
				(width 0.1)
				(type default)
			)
			(layer "B.Fab")
		)
		(fp_line
			(start -0.12065 -0.3048)
			(end -0.67945 -0.3048)
			(stroke
				(width 0.1)
				(type default)
			)
			(layer "B.Fab")
		)
		(fp_line
			(start -0.12065 -0.2794)
			(end -0.12065 -0.3048)
			(stroke
				(width 0.1)
				(type default)
			)
			(layer "B.Fab")
		)
		(fp_line
			(start -0.120396 0.2794)
			(end 0.12065 0.2794)
			(stroke
				(width 0.1)
				(type default)
			)
			(layer "B.Fab")
		)
		(fp_line
			(start -0.120396 0.3048)
			(end -0.120396 0.2794)
			(stroke
				(width 0.1)
				(type default)
			)
			(layer "B.Fab")
		)
		(fp_line
			(start 0.12065 -0.305054)
			(end 0.12065 -0.2794)
			(stroke
				(width 0.1)
				(type default)
			)
			(layer "B.Fab")
		)
		(fp_line
			(start 0.12065 -0.2794)
			(end -0.12065 -0.2794)
			(stroke
				(width 0.1)
				(type default)
			)
			(layer "B.Fab")
		)
		(fp_line
			(start 0.12065 0.2794)
			(end 0.12065 0.3048)
			(stroke
				(width 0.1)
				(type default)
			)
			(layer "B.Fab")
		)
		(fp_line
			(start 0.12065 0.3048)
			(end 0.67945 0.3048)
			(stroke
				(width 0.1)
				(type default)
			)
			(layer "B.Fab")
		)
		(fp_line
			(start 0.67945 -0.305054)
			(end 0.12065 -0.305054)
			(stroke
				(width 0.1)
				(type default)
			)
			(layer "B.Fab")
		)
		(fp_line
			(start 0.67945 0.3048)
			(end 0.67945 -0.305054)
			(stroke
				(width 0.1)
				(type default)
			)
			(layer "B.Fab")
		)
		(pad "1" smd circle
			(at 0.40005 0 180)
			(size 0 0)
			(layers "B.Cu" "B.Mask" "B.Paste")
			(net "P5V_AUX")
		)
		(pad "2" smd circle
			(at -0.40005 0 180)
			(size 0 0)
			(layers "B.Cu" "B.Mask" "B.Paste")
			(net "PVDDCR_CPU1_P1_VMON")
		)
	)
	(footprint ""
		(layer "B.Cu")
		(at 107.677204 -261.748016 90)
		(property "Reference" "C3921"
			(at 0 0 90)
			(layer "B.SilkS")
			(hide yes)
			(effects
				(font
					(size 1.27 1.27)
				)
				(justify mirror)
			)
		)
		(property "Value" ""
			(at 0 0 90)
			(layer "B.Fab")
			(effects
				(font
					(size 1.27 1.27)
				)
				(justify mirror)
			)
		)
		(duplicate_pad_numbers_are_jumpers no)
		(fp_line
			(start 0.7874 -0.4064)
			(end -0.7874 -0.4064)
			(stroke
				(width 0.1524)
				(type default)
			)
			(layer "B.SilkS")
		)
		(fp_line
			(start -0.7874 -0.4064)
			(end -0.7874 0.4064)
			(stroke
				(width 0.1524)
				(type default)
			)
			(layer "B.SilkS")
		)
		(fp_line
			(start 0.7874 0.4064)
			(end 0.7874 -0.4064)
			(stroke
				(width 0.1524)
				(type default)
			)
			(layer "B.SilkS")
		)
		(fp_line
			(start -0.7874 0.4064)
			(end 0.7874 0.4064)
			(stroke
				(width 0.1524)
				(type default)
			)
			(layer "B.SilkS")
		)
		(fp_line
			(start 0.67945 -0.305054)
			(end 0.12065 -0.305054)
			(stroke
				(width 0.1)
				(type default)
			)
			(layer "B.Fab")
		)
		(fp_line
			(start 0.12065 -0.305054)
			(end 0.12065 -0.2794)
			(stroke
				(width 0.1)
				(type default)
			)
			(layer "B.Fab")
		)
		(fp_line
			(start -0.12065 -0.3048)
			(end -0.67945 -0.3048)
			(stroke
				(width 0.1)
				(type default)
			)
			(layer "B.Fab")
		)
		(fp_line
			(start -0.67945 -0.3048)
			(end -0.67945 0.3048)
			(stroke
				(width 0.1)
				(type default)
			)
			(layer "B.Fab")
		)
		(fp_line
			(start 0.12065 -0.2794)
			(end -0.12065 -0.2794)
			(stroke
				(width 0.1)
				(type default)
			)
			(layer "B.Fab")
		)
		(fp_line
			(start -0.12065 -0.2794)
			(end -0.12065 -0.3048)
			(stroke
				(width 0.1)
				(type default)
			)
			(layer "B.Fab")
		)
		(fp_line
			(start 0.12065 0.2794)
			(end 0.12065 0.3048)
			(stroke
				(width 0.1)
				(type default)
			)
			(layer "B.Fab")
		)
		(fp_line
			(start -0.120396 0.2794)
			(end 0.12065 0.2794)
			(stroke
				(width 0.1)
				(type default)
			)
			(layer "B.Fab")
		)
		(fp_line
			(start 0.67945 0.3048)
			(end 0.67945 -0.305054)
			(stroke
				(width 0.1)
				(type default)
			)
			(layer "B.Fab")
		)
		(fp_line
			(start 0.12065 0.3048)
			(end 0.67945 0.3048)
			(stroke
				(width 0.1)
				(type default)
			)
			(layer "B.Fab")
		)
		(fp_line
			(start -0.120396 0.3048)
			(end -0.120396 0.2794)
			(stroke
				(width 0.1)
				(type default)
			)
			(layer "B.Fab")
		)
		(fp_line
			(start -0.67945 0.3048)
			(end -0.120396 0.3048)
			(stroke
				(width 0.1)
				(type default)
			)
			(layer "B.Fab")
		)
		(pad "1" smd circle
			(at 0.40005 0 270)
			(size 0 0)
			(layers "B.Cu" "B.Mask" "B.Paste")
			(net "PVDD11_S3_P1")
		)
		(pad "2" smd circle
			(at -0.40005 0 270)
			(size 0 0)
			(layers "B.Cu" "B.Mask" "B.Paste")
			(net "GND")
		)
	)
	(footprint ""
		(layer "B.Cu")
		(at 64.616584 -408.517344 90)
		(property "Reference" "C6672"
			(at 0 0 90)
			(layer "B.SilkS")
			(hide yes)
			(effects
				(font
					(size 1.27 1.27)
				)
				(justify mirror)
			)
		)
		(property "Value" ""
			(at 0 0 90)
			(layer "B.Fab")
			(effects
				(font
					(size 1.27 1.27)
				)
				(justify mirror)
			)
		)
		(duplicate_pad_numbers_are_jumpers no)
		(fp_line
			(start 0.299974 -0.150114)
			(end -0.299974 -0.150114)
			(stroke
				(width 0.1)
				(type default)
			)
			(layer "B.Fab")
		)
		(fp_line
			(start -0.299974 -0.150114)
			(end -0.299974 0.150114)
			(stroke
				(width 0.1)
				(type default)
			)
			(layer "B.Fab")
		)
		(fp_line
			(start 0.299974 0.150114)
			(end 0.299974 -0.150114)
			(stroke
				(width 0.1)
				(type default)
			)
			(layer "B.Fab")
		)
		(fp_line
			(start -0.299974 0.150114)
			(end 0.299974 0.150114)
			(stroke
				(width 0.1)
				(type default)
			)
			(layer "B.Fab")
		)
		(pad "1" smd rect
			(at 0.2667 0 270)
			(size 0.3048 0.381)
			(layers "B.Cu" "B.Mask" "B.Paste")
			(net "P5E_CPU1_P1_TX_BUF_C_DN<5>")
		)
		(pad "2" smd rect
			(at -0.2667 0 270)
			(size 0.3048 0.381)
			(layers "B.Cu" "B.Mask" "B.Paste")
			(net "P5E_CPU1_P1_TX_BUF_DN<5>")
		)
	)
)
